(kicad_pcb
	(version 20240108)
	(generator "pcbnew")
	(generator_version "8.0")
	(general
		(thickness 1.6)
		(legacy_teardrops no)
	)
	(paper "A4")
	(title_block
		(title "Jetson Orin Baseboard OCuLink Expansion")
		(date "2025-03-18")
		(rev "1.1.0")
		(company "Antmicro Ltd")
		(comment 1 "www.antmicro.com")
		(comment 9 "footprints 34-37 of 119")
	)
	(layers
		(0 "F.Cu" signal)
		(1 "In1.Cu" signal)
		(2 "In2.Cu" signal)
		(31 "B.Cu" signal)
		(32 "B.Adhes" user "B.Adhesive")
		(33 "F.Adhes" user "F.Adhesive")
		(34 "B.Paste" user)
		(35 "F.Paste" user)
		(36 "B.SilkS" user "B.Silkscreen")
		(37 "F.SilkS" user "F.Silkscreen")
		(38 "B.Mask" user)
		(39 "F.Mask" user)
		(40 "Dwgs.User" user "User.Drawings")
		(41 "Cmts.User" user "User.Comments")
		(42 "Eco1.User" user "User.Eco1")
		(43 "Eco2.User" user "User.Eco2")
		(44 "Edge.Cuts" user)
		(45 "Margin" user)
		(46 "B.CrtYd" user "B.Courtyard")
		(47 "F.CrtYd" user "F.Courtyard")
		(48 "B.Fab" user)
		(49 "F.Fab" user)
	)
	(footprint "antmicro-footprints:R_0402_1005Metric"
		(layer "F.Cu")
		(at 117.79 130.14 180)
		(descr "Resistor SMD 0402")
		(tags "resistor SMD 0402")
		(property "Reference" "R32"
			(at -1.122484 -0.772697 0)
			(layer "F.SilkS")
			(effects
				(font
					(size 0.7 0.7)
					(thickness 0.15)
				)
				(justify right top)
			)
		)
		(property "Value" "R_0R_0402"
			(at -1.011843 1.772047 0)
			(layer "F.Fab")
			(effects
				(font
					(size 0.7 0.7)
					(thickness 0.15)
				)
				(justify right top)
			)
		)
		(property "Footprint" "antmicro-footprints:R_0402_1005Metric"
			(at 0 0 0)
			(layer "F.Fab")
			(hide yes)
			(effects
				(font
					(size 1.27 1.27)
					(thickness 0.15)
				)
			)
		)
		(property "Datasheet" "https://industrial.panasonic.com/cdbs/www-data/pdf/RDA0000/AOA0000C301.pdf"
			(at 0 0 0)
			(layer "F.Fab")
			(hide yes)
			(effects
				(font
					(size 1.27 1.27)
					(thickness 0.15)
				)
			)
		)
		(property "Description" "SMD Chip Resistor, Jumper, 0 ohm, 100 mW, 0402 [1005 Metric], Thick Film, General Purpose"
			(at 0 0 0)
			(layer "F.Fab")
			(hide yes)
			(effects
				(font
					(size 1.27 1.27)
					(thickness 0.15)
				)
			)
		)
		(property "MPN" "ERJ2GE0R00X"
			(at 0 0 180)
			(unlocked yes)
			(layer "F.Fab")
			(hide yes)
			(effects
				(font
					(size 1 1)
					(thickness 0.15)
				)
			)
		)
		(property "Manufacturer" "Panasonic"
			(at 0 0 180)
			(unlocked yes)
			(layer "F.Fab")
			(hide yes)
			(effects
				(font
					(size 1 1)
					(thickness 0.15)
				)
			)
		)
		(property "License" "Apache-2.0"
			(at 0 0 180)
			(unlocked yes)
			(layer "F.Fab")
			(hide yes)
			(effects
				(font
					(size 1 1)
					(thickness 0.15)
				)
			)
		)
		(property "Author" "Antmicro"
			(at 0 0 180)
			(unlocked yes)
			(layer "F.Fab")
			(hide yes)
			(effects
				(font
					(size 1 1)
					(thickness 0.15)
				)
			)
		)
		(property "Val" "0R"
			(at 0 0 180)
			(unlocked yes)
			(layer "F.Fab")
			(hide yes)
			(effects
				(font
					(size 1 1)
					(thickness 0.15)
				)
			)
		)
		(property "Tolerance" ""
			(at 0 0 180)
			(unlocked yes)
			(layer "F.Fab")
			(hide yes)
			(effects
				(font
					(size 1 1)
					(thickness 0.15)
				)
			)
		)
		(property "Current" "1A"
			(at 0 0 180)
			(unlocked yes)
			(layer "F.Fab")
			(hide yes)
			(effects
				(font
					(size 1 1)
					(thickness 0.15)
				)
			)
		)
		(property "Public" "False"
			(at 0 0 180)
			(unlocked yes)
			(layer "F.Fab")
			(hide yes)
			(effects
				(font
					(size 1 1)
					(thickness 0.15)
				)
			)
		)
		(sheetname "Root")
		(sheetfile "jetson-orin-baseboard-oculink-expansion.kicad_sch")
		(attr smd)
		(fp_rect
			(start -0.925 -0.47)
			(end 0.925 0.47)
			(stroke
				(width 0.05)
				(type default)
			)
			(fill none)
			(layer "F.CrtYd")
		)
		(fp_rect
			(start -0.5 -0.25)
			(end 0.5 0.25)
			(stroke
				(width 0.15)
				(type solid)
			)
			(fill none)
			(layer "F.Fab")
		)
		(fp_text user "License: Apache-2.0"
			(at -0.95 5.169 0)
			(layer "F.Fab")
			(hide yes)
			(effects
				(font
					(size 0.7 0.7)
					(thickness 0.15)
				)
				(justify right top)
			)
		)
		(fp_text user "${REFERENCE}"
			(at -0.95 3.168 0)
			(layer "F.Fab")
			(hide yes)
			(effects
				(font
					(size 0.7 0.7)
					(thickness 0.15)
				)
				(justify right top)
			)
		)
		(fp_text user "Author: Antmicro"
			(at -0.95 4.169 0)
			(layer "F.Fab")
			(hide yes)
			(effects
				(font
					(size 0.7 0.7)
					(thickness 0.15)
				)
				(justify right top)
			)
		)
		(pad "1" smd roundrect
			(at -0.48 0 180)
			(size 0.59 0.64)
			(layers "F.Cu" "F.Paste" "F.Mask")
			(roundrect_rratio 0.25)
			(net 23 "+3V3")
			(pintype "passive")
		)
		(pad "2" smd roundrect
			(at 0.48 0 180)
			(size 0.59 0.64)
			(layers "F.Cu" "F.Paste" "F.Mask")
			(roundrect_rratio 0.25)
			(net 104 "Net-(U3-RXDET)")
			(pintype "passive")
		)
	)
	(footprint "antmicro-footprints:R_0402_1005Metric"
		(layer "F.Cu")
		(at 146.2 122.15 -90)
		(descr "Resistor SMD 0402")
		(tags "resistor SMD 0402")
		(property "Reference" "R50"
			(at -1.05 -0.5 90)
			(layer "F.SilkS")
			(effects
				(font
					(size 0.7 0.7)
					(thickness 0.15)
				)
				(justify right top)
			)
		)
		(property "Value" "R_0R_0402"
			(at -1.011843 1.772047 90)
			(layer "F.Fab")
			(effects
				(font
					(size 0.7 0.7)
					(thickness 0.15)
				)
				(justify right top)
			)
		)
		(property "Footprint" "antmicro-footprints:R_0402_1005Metric"
			(at 0 0 90)
			(layer "F.Fab")
			(hide yes)
			(effects
				(font
					(size 1.27 1.27)
					(thickness 0.15)
				)
			)
		)
		(property "Datasheet" "https://industrial.panasonic.com/cdbs/www-data/pdf/RDA0000/AOA0000C301.pdf"
			(at 0 0 90)
			(layer "F.Fab")
			(hide yes)
			(effects
				(font
					(size 1.27 1.27)
					(thickness 0.15)
				)
			)
		)
		(property "Description" "SMD Chip Resistor, Jumper, 0 ohm, 100 mW, 0402 [1005 Metric], Thick Film, General Purpose"
			(at 0 0 90)
			(layer "F.Fab")
			(hide yes)
			(effects
				(font
					(size 1.27 1.27)
					(thickness 0.15)
				)
			)
		)
		(property "MPN" "ERJ2GE0R00X"
			(at 0 0 -90)
			(unlocked yes)
			(layer "F.Fab")
			(hide yes)
			(effects
				(font
					(size 1 1)
					(thickness 0.15)
				)
			)
		)
		(property "Manufacturer" "Panasonic"
			(at 0 0 -90)
			(unlocked yes)
			(layer "F.Fab")
			(hide yes)
			(effects
				(font
					(size 1 1)
					(thickness 0.15)
				)
			)
		)
		(property "License" "Apache-2.0"
			(at 0 0 -90)
			(unlocked yes)
			(layer "F.Fab")
			(hide yes)
			(effects
				(font
					(size 1 1)
					(thickness 0.15)
				)
			)
		)
		(property "Author" "Antmicro"
			(at 0 0 -90)
			(unlocked yes)
			(layer "F.Fab")
			(hide yes)
			(effects
				(font
					(size 1 1)
					(thickness 0.15)
				)
			)
		)
		(property "Val" "0R"
			(at 0 0 -90)
			(unlocked yes)
			(layer "F.Fab")
			(hide yes)
			(effects
				(font
					(size 1 1)
					(thickness 0.15)
				)
			)
		)
		(property "Tolerance" ""
			(at 0 0 -90)
			(unlocked yes)
			(layer "F.Fab")
			(hide yes)
			(effects
				(font
					(size 1 1)
					(thickness 0.15)
				)
			)
		)
		(property "Current" "1A"
			(at 0 0 -90)
			(unlocked yes)
			(layer "F.Fab")
			(hide yes)
			(effects
				(font
					(size 1 1)
					(thickness 0.15)
				)
			)
		)
		(sheetname "Root")
		(sheetfile "jetson-orin-baseboard-oculink-expansion.kicad_sch")
		(attr smd)
		(fp_rect
			(start -0.925 -0.47)
			(end 0.925 0.47)
			(stroke
				(width 0.05)
				(type default)
			)
			(fill none)
			(layer "F.CrtYd")
		)
		(fp_rect
			(start -0.5 -0.25)
			(end 0.5 0.25)
			(stroke
				(width 0.15)
				(type solid)
			)
			(fill none)
			(layer "F.Fab")
		)
		(fp_text user "License: Apache-2.0"
			(at -0.95 5.169 90)
			(layer "F.Fab")
			(hide yes)
			(effects
				(font
					(size 0.7 0.7)
					(thickness 0.15)
				)
				(justify right top)
			)
		)
		(fp_text user "${REFERENCE}"
			(at -0.95 3.168 90)
			(layer "F.Fab")
			(hide yes)
			(effects
				(font
					(size 0.7 0.7)
					(thickness 0.15)
				)
				(justify right top)
			)
		)
		(fp_text user "Author: Antmicro"
			(at -0.95 4.169 90)
			(layer "F.Fab")
			(hide yes)
			(effects
				(font
					(size 0.7 0.7)
					(thickness 0.15)
				)
				(justify right top)
			)
		)
		(pad "1" smd roundrect
			(at -0.48 0 270)
			(size 0.59 0.64)
			(layers "F.Cu" "F.Paste" "F.Mask")
			(roundrect_rratio 0.25)
			(net 135 "Net-(U5-OUT)")
			(pintype "passive")
		)
		(pad "2" smd roundrect
			(at 0.48 0 270)
			(size 0.59 0.64)
			(layers "F.Cu" "F.Paste" "F.Mask")
			(roundrect_rratio 0.25)
			(net 133 "+5V_OCU")
			(pintype "passive")
		)
	)
	(footprint "antmicro-footprints:C_0402_1005Metric"
		(layer "F.Cu")
		(at 143.046 127.151 90)
		(descr "Capacitor SMD 0402")
		(tags "capacitor SMD 0402")
		(property "Reference" "C33"
			(at -1.1 -0.546 90)
			(layer "F.SilkS")
			(effects
				(font
					(size 0.7 0.7)
					(thickness 0.15)
				)
				(justify left bottom)
			)
		)
		(property "Value" "C_10u_0402"
			(at -1.022927 2.155213 90)
			(layer "F.Fab")
			(effects
				(font
					(size 0.7 0.7)
					(thickness 0.15)
				)
				(justify left bottom)
			)
		)
		(property "Footprint" "antmicro-footprints:C_0402_1005Metric"
			(at 0 0 90)
			(layer "F.Fab")
			(hide yes)
			(effects
				(font
					(size 1.27 1.27)
					(thickness 0.15)
				)
			)
		)
		(property "Datasheet" "https://www.yageo.com/en/Chart/Download/pdf/CC0402MRX5R5BB106"
			(at 0 0 90)
			(layer "F.Fab")
			(hide yes)
			(effects
				(font
					(size 1.27 1.27)
					(thickness 0.15)
				)
			)
		)
		(property "Description" "SMD Multilayer Ceramic Capacitor, 10 µF, 6.3 V, 0402 [1005 Metric], ± 20%, X5R, CC Series"
			(at 0 0 90)
			(layer "F.Fab")
			(hide yes)
			(effects
				(font
					(size 1.27 1.27)
					(thickness 0.15)
				)
			)
		)
		(property "MPN" "CC0402MRX5R5BB106"
			(at 0 0 90)
			(unlocked yes)
			(layer "F.Fab")
			(hide yes)
			(effects
				(font
					(size 1 1)
					(thickness 0.15)
				)
			)
		)
		(property "Manufacturer" "YAGEO"
			(at 0 0 90)
			(unlocked yes)
			(layer "F.Fab")
			(hide yes)
			(effects
				(font
					(size 1 1)
					(thickness 0.15)
				)
			)
		)
		(property "License" "Apache-2.0"
			(at 0 0 90)
			(unlocked yes)
			(layer "F.Fab")
			(hide yes)
			(effects
				(font
					(size 1 1)
					(thickness 0.15)
				)
			)
		)
		(property "Author" "Antmicro"
			(at 0 0 90)
			(unlocked yes)
			(layer "F.Fab")
			(hide yes)
			(effects
				(font
					(size 1 1)
					(thickness 0.15)
				)
			)
		)
		(property "Val" "10u"
			(at 0 0 90)
			(unlocked yes)
			(layer "F.Fab")
			(hide yes)
			(effects
				(font
					(size 1 1)
					(thickness 0.15)
				)
			)
		)
		(property "Voltage" ""
			(at 0 0 90)
			(unlocked yes)
			(layer "F.Fab")
			(hide yes)
			(effects
				(font
					(size 1 1)
					(thickness 0.15)
				)
			)
		)
		(property "Dielectric" ""
			(at 0 0 90)
			(unlocked yes)
			(layer "F.Fab")
			(hide yes)
			(effects
				(font
					(size 1 1)
					(thickness 0.15)
				)
			)
		)
		(sheetname "Root")
		(sheetfile "jetson-orin-baseboard-oculink-expansion.kicad_sch")
		(attr smd)
		(fp_rect
			(start -0.925 -0.47)
			(end 0.925 0.47)
			(stroke
				(width 0.05)
				(type default)
			)
			(fill none)
			(layer "F.CrtYd")
		)
		(fp_line
			(start 0.504 -0.25)
			(end 0.504 0.248)
			(stroke
				(width 0.15)
				(type solid)
			)
			(layer "F.Fab")
		)
		(fp_line
			(start -0.494 -0.25)
			(end 0.504 -0.25)
			(stroke
				(width 0.15)
				(type solid)
			)
			(layer "F.Fab")
		)
		(fp_line
			(start 0.504 0.248)
			(end -0.494 0.248)
			(stroke
				(width 0.15)
				(type solid)
			)
			(layer "F.Fab")
		)
		(fp_line
			(start -0.494 0.248)
			(end -0.494 -0.25)
			(stroke
				(width 0.15)
				(type solid)
			)
			(layer "F.Fab")
		)
		(fp_text user "Author: Antmicro"
			(at -0.939 3.399 90)
			(layer "F.Fab")
			(hide yes)
			(effects
				(font
					(size 0.7 0.7)
					(thickness 0.15)
				)
				(justify left bottom)
			)
		)
		(fp_text user "License: Apache-2.0"
			(at -0.939 5.799 90)
			(layer "F.Fab")
			(hide yes)
			(effects
				(font
					(size 0.7 0.7)
					(thickness 0.15)
				)
				(justify left bottom)
			)
		)
		(fp_text user "${REFERENCE}"
			(at -0.939 4.599 90)
			(layer "F.Fab")
			(hide yes)
			(effects
				(font
					(size 0.7 0.7)
					(thickness 0.15)
				)
				(justify left bottom)
			)
		)
		(pad "1" smd roundrect
			(at -0.48 0 90)
			(size 0.59 0.64)
			(layers "F.Cu" "F.Paste" "F.Mask")
			(roundrect_rratio 0.25)
			(net 51 "GND")
			(pintype "passive")
		)
		(pad "2" smd roundrect
			(at 0.48 0 90)
			(size 0.59 0.64)
			(layers "F.Cu" "F.Paste" "F.Mask")
			(roundrect_rratio 0.25)
			(net 52 "+5V")
			(pintype "passive")
		)
	)
	(footprint "antmicro-footprints:R_0402_1005Metric"
		(layer "F.Cu")
		(at 145.554 114.56 90)
		(descr "Resistor SMD 0402")
		(tags "resistor SMD 0402")
		(property "Reference" "R43"
			(at -1.04 1.646 90)
			(layer "F.SilkS")
			(effects
				(font
					(size 0.7 0.7)
					(thickness 0.15)
				)
				(justify left bottom)
			)
		)
		(property "Value" "R_10k_0402"
			(at -1.011843 1.772047 90)
			(layer "F.Fab")
			(effects
				(font
					(size 0.7 0.7)
					(thickness 0.15)
				)
				(justify left bottom)
			)
		)
		(property "Footprint" "antmicro-footprints:R_0402_1005Metric"
			(at 0 0 90)
			(layer "F.Fab")
			(hide yes)
			(effects
				(font
					(size 1.27 1.27)
					(thickness 0.15)
				)
			)
		)
		(property "Datasheet" "https://www.bourns.com/docs/product-datasheets/cr.pdf"
			(at 0 0 90)
			(layer "F.Fab")
			(hide yes)
			(effects
				(font
					(size 1.27 1.27)
					(thickness 0.15)
				)
			)
		)
		(property "Description" "SMD Chip Resistor, 10 kohm, ± 1%, 62.5 mW, 0402 [1005 Metric], Thick Film, General Purpose"
			(at 0 0 90)
			(layer "F.Fab")
			(hide yes)
			(effects
				(font
					(size 1.27 1.27)
					(thickness 0.15)
				)
			)
		)
		(property "MPN" "CR0402-FX-1002GLF"
			(at 0 0 90)
			(unlocked yes)
			(layer "F.Fab")
			(hide yes)
			(effects
				(font
					(size 1 1)
					(thickness 0.15)
				)
			)
		)
		(property "Manufacturer" "Bourns"
			(at 0 0 90)
			(unlocked yes)
			(layer "F.Fab")
			(hide yes)
			(effects
				(font
					(size 1 1)
					(thickness 0.15)
				)
			)
		)
		(property "License" "Apache-2.0"
			(at 0 0 90)
			(unlocked yes)
			(layer "F.Fab")
			(hide yes)
			(effects
				(font
					(size 1 1)
					(thickness 0.15)
				)
			)
		)
		(property "Author" "Antmicro"
			(at 0 0 90)
			(unlocked yes)
			(layer "F.Fab")
			(hide yes)
			(effects
				(font
					(size 1 1)
					(thickness 0.15)
				)
			)
		)
		(property "Val" "10k"
			(at 0 0 90)
			(unlocked yes)
			(layer "F.Fab")
			(hide yes)
			(effects
				(font
					(size 1 1)
					(thickness 0.15)
				)
			)
		)
		(property "Tolerance" "1%"
			(at 0 0 90)
			(unlocked yes)
			(layer "F.Fab")
			(hide yes)
			(effects
				(font
					(size 1 1)
					(thickness 0.15)
				)
			)
		)
		(sheetname "Root")
		(sheetfile "jetson-orin-baseboard-oculink-expansion.kicad_sch")
		(attr smd)
		(fp_rect
			(start -0.925 -0.47)
			(end 0.925 0.47)
			(stroke
				(width 0.05)
				(type default)
			)
			(fill none)
			(layer "F.CrtYd")
		)
		(fp_rect
			(start -0.5 -0.25)
			(end 0.5 0.25)
			(stroke
				(width 0.15)
				(type solid)
			)
			(fill none)
			(layer "F.Fab")
		)
		(fp_text user "License: Apache-2.0"
			(at -0.95 5.169 90)
			(layer "F.Fab")
			(hide yes)
			(effects
				(font
					(size 0.7 0.7)
					(thickness 0.15)
				)
				(justify left bottom)
			)
		)
		(fp_text user "${REFERENCE}"
			(at -0.95 3.168 90)
			(layer "F.Fab")
			(hide yes)
			(effects
				(font
					(size 0.7 0.7)
					(thickness 0.15)
				)
				(justify left bottom)
			)
		)
		(fp_text user "Author: Antmicro"
			(at -0.95 4.169 90)
			(layer "F.Fab")
			(hide yes)
			(effects
				(font
					(size 0.7 0.7)
					(thickness 0.15)
				)
				(justify left bottom)
			)
		)
		(pad "1" smd roundrect
			(at -0.48 0 90)
			(size 0.59 0.64)
			(layers "F.Cu" "F.Paste" "F.Mask")
			(roundrect_rratio 0.25)
			(net 23 "+3V3")
			(pintype "passive")
		)
		(pad "2" smd roundrect
			(at 0.48 0 90)
			(size 0.59 0.64)
			(layers "F.Cu" "F.Paste" "F.Mask")
			(roundrect_rratio 0.25)
			(net 136 "Net-(U4-FLG)")
			(pintype "passive")
		)
	)
)
